# T6G (Grand Teton) — schematic netlist excerpt (pin names and nets, part order shuffled) for the footprints in the layout excerpt that follows; sources: Cadence DE-HDL packaged netlist, KiCad conversion of 04192023_DAF0TMB3IC0_F0TG_MB_C_brd_V02_OCP.brd

C1881  Q_CAP  0.1UF 25V 10% X7R  pkg 0402  page 127 : A = GPU_FPGA_READY_ISO ; B = GND
C2357  Q_CAP  22UF 4V 20% X6S  pkg C0402  page 73 : A = PVDDCR_CPU1_P1 ; B = GND

(kicad_pcb
	(version 20260206)
	(generator "pcbnew")
	(generator_version "10.0")
	(general
		(thickness 1.6)
		(legacy_teardrops no)
	)
	(paper "A4")
	(title_block
		(title "04192023_DAF0TMB3IC0_F0TG_MB_C_brd_V02_OCP.brd")
		(comment 1 "Grand Teton / footprints 6995-6996 of 8354")
	)
	(layers
		(0 "F.Cu" signal "TOP")
		(4 "In1.Cu" signal "GND")
		(6 "In2.Cu" signal "IN1")
		(8 "In3.Cu" signal "GND1")
		(10 "In4.Cu" signal "IN2")
		(12 "In5.Cu" signal "GND2")
		(14 "In6.Cu" signal "IN3")
		(16 "In7.Cu" signal "GND3")
		(18 "In8.Cu" signal "VCC")
		(20 "In9.Cu" signal "VCC1")
		(22 "In10.Cu" signal "GND4")
		(24 "In11.Cu" signal "IN4")
		(26 "In12.Cu" signal "GND5")
		(28 "In13.Cu" signal "IN5")
		(30 "In14.Cu" signal "GND6")
		(32 "In15.Cu" signal "IN6")
		(34 "In16.Cu" signal "GND7")
		(2 "B.Cu" signal "BOTTOM")
		(9 "F.Adhes" user "F.Adhesive")
		(11 "B.Adhes" user "B.Adhesive")
		(13 "F.Paste" user "Package Geometry/Pastemask Top")
		(15 "B.Paste" user "Package Geometry/Pastemask Bottom")
		(5 "F.SilkS" user "Ref Des/Silkscreen Top")
		(7 "B.SilkS" user "Ref Des/Silkscreen Bottom")
		(1 "F.Mask" user "Board Geometry/Soldermask Top")
		(3 "B.Mask" user "Board Geometry/Soldermask Bottom")
		(17 "Dwgs.User" user "User.Drawings")
		(19 "Cmts.User" user "User.Comments")
		(21 "Eco1.User" user "User.Eco1")
		(23 "Eco2.User" user "User.Eco2")
		(25 "Edge.Cuts" user "Board Geometry/Outline")
		(27 "Margin" user)
		(31 "F.CrtYd" user "Package Geometry/Place Bound Top")
		(29 "B.CrtYd" user "Package Geometry/Place Bound Bottom")
		(35 "F.Fab" user "Ref Des/Assembly Top")
		(33 "B.Fab" user "Ref Des/Assembly Bottom")
	)
	(footprint ""
		(layer "B.Cu")
		(at 51.415442 -421.17518)
		(property "Reference" "C1881"
			(at 0 0 0)
			(layer "B.SilkS")
			(hide yes)
			(effects
				(font
					(size 1.27 1.27)
				)
				(justify mirror)
			)
		)
		(property "Value" ""
			(at 0 0 0)
			(layer "B.Fab")
			(effects
				(font
					(size 1.27 1.27)
				)
				(justify mirror)
			)
		)
		(duplicate_pad_numbers_are_jumpers no)
		(fp_line
			(start -0.7874 -0.4064)
			(end -0.7874 0.4064)
			(stroke
				(width 0.1524)
				(type default)
			)
			(layer "B.SilkS")
		)
		(fp_line
			(start -0.7874 0.4064)
			(end 0.7874 0.4064)
			(stroke
				(width 0.1524)
				(type default)
			)
			(layer "B.SilkS")
		)
		(fp_line
			(start 0.7874 -0.4064)
			(end -0.7874 -0.4064)
			(stroke
				(width 0.1524)
				(type default)
			)
			(layer "B.SilkS")
		)
		(fp_line
			(start 0.7874 0.4064)
			(end 0.7874 -0.4064)
			(stroke
				(width 0.1524)
				(type default)
			)
			(layer "B.SilkS")
		)
		(fp_line
			(start -0.67945 -0.3048)
			(end -0.67945 0.3048)
			(stroke
				(width 0.1)
				(type default)
			)
			(layer "B.Fab")
		)
		(fp_line
			(start -0.67945 0.3048)
			(end -0.120396 0.3048)
			(stroke
				(width 0.1)
				(type default)
			)
			(layer "B.Fab")
		)
		(fp_line
			(start -0.12065 -0.3048)
			(end -0.67945 -0.3048)
			(stroke
				(width 0.1)
				(type default)
			)
			(layer "B.Fab")
		)
		(fp_line
			(start -0.12065 -0.2794)
			(end -0.12065 -0.3048)
			(stroke
				(width 0.1)
				(type default)
			)
			(layer "B.Fab")
		)
		(fp_line
			(start -0.120396 0.2794)
			(end 0.12065 0.2794)
			(stroke
				(width 0.1)
				(type default)
			)
			(layer "B.Fab")
		)
		(fp_line
			(start -0.120396 0.3048)
			(end -0.120396 0.2794)
			(stroke
				(width 0.1)
				(type default)
			)
			(layer "B.Fab")
		)
		(fp_line
			(start 0.12065 -0.305054)
			(end 0.12065 -0.2794)
			(stroke
				(width 0.1)
				(type default)
			)
			(layer "B.Fab")
		)
		(fp_line
			(start 0.12065 -0.2794)
			(end -0.12065 -0.2794)
			(stroke
				(width 0.1)
				(type default)
			)
			(layer "B.Fab")
		)
		(fp_line
			(start 0.12065 0.2794)
			(end 0.12065 0.3048)
			(stroke
				(width 0.1)
				(type default)
			)
			(layer "B.Fab")
		)
		(fp_line
			(start 0.12065 0.3048)
			(end 0.67945 0.3048)
			(stroke
				(width 0.1)
				(type default)
			)
			(layer "B.Fab")
		)
		(fp_line
			(start 0.67945 -0.305054)
			(end 0.12065 -0.305054)
			(stroke
				(width 0.1)
				(type default)
			)
			(layer "B.Fab")
		)
		(fp_line
			(start 0.67945 0.3048)
			(end 0.67945 -0.305054)
			(stroke
				(width 0.1)
				(type default)
			)
			(layer "B.Fab")
		)
		(pad "1" smd circle
			(at 0.40005 0 180)
			(size 0 0)
			(layers "B.Cu" "B.Mask" "B.Paste")
			(net "GPU_FPGA_READY_ISO")
		)
		(pad "2" smd circle
			(at -0.40005 0 180)
			(size 0 0)
			(layers "B.Cu" "B.Mask" "B.Paste")
			(net "GND")
		)
	)
	(footprint ""
		(layer "B.Cu")
		(at 108.907834 -271.395952)
		(property "Reference" "C2357"
			(at 0 0 0)
			(layer "B.SilkS")
			(hide yes)
			(effects
				(font
					(size 1.27 1.27)
				)
				(justify mirror)
			)
		)
		(property "Value" ""
			(at 0 0 0)
			(layer "B.Fab")
			(effects
				(font
					(size 1.27 1.27)
				)
				(justify mirror)
			)
		)
		(duplicate_pad_numbers_are_jumpers no)
		(fp_line
			(start -0.7874 -0.4064)
			(end -0.7874 0.4064)
			(stroke
				(width 0.1524)
				(type default)
			)
			(layer "B.SilkS")
		)
		(fp_line
			(start -0.7874 0.4064)
			(end 0.7874 0.4064)
			(stroke
				(width 0.1524)
				(type default)
			)
			(layer "B.SilkS")
		)
		(fp_line
			(start 0.7874 -0.4064)
			(end -0.7874 -0.4064)
			(stroke
				(width 0.1524)
				(type default)
			)
			(layer "B.SilkS")
		)
		(fp_line
			(start 0.7874 0.4064)
			(end 0.7874 -0.4064)
			(stroke
				(width 0.1524)
				(type default)
			)
			(layer "B.SilkS")
		)
		(fp_line
			(start -0.67945 -0.3048)
			(end -0.67945 0.3048)
			(stroke
				(width 0.1)
				(type default)
			)
			(layer "B.Fab")
		)
		(fp_line
			(start -0.67945 0.3048)
			(end -0.120396 0.3048)
			(stroke
				(width 0.1)
				(type default)
			)
			(layer "B.Fab")
		)
		(fp_line
			(start -0.12065 -0.3048)
			(end -0.67945 -0.3048)
			(stroke
				(width 0.1)
				(type default)
			)
			(layer "B.Fab")
		)
		(fp_line
			(start -0.12065 -0.2794)
			(end -0.12065 -0.3048)
			(stroke
				(width 0.1)
				(type default)
			)
			(layer "B.Fab")
		)
		(fp_line
			(start -0.120396 0.2794)
			(end 0.12065 0.2794)
			(stroke
				(width 0.1)
				(type default)
			)
			(layer "B.Fab")
		)
		(fp_line
			(start -0.120396 0.3048)
			(end -0.120396 0.2794)
			(stroke
				(width 0.1)
				(type default)
			)
			(layer "B.Fab")
		)
		(fp_line
			(start 0.12065 -0.305054)
			(end 0.12065 -0.2794)
			(stroke
				(width 0.1)
				(type default)
			)
			(layer "B.Fab")
		)
		(fp_line
			(start 0.12065 -0.2794)
			(end -0.12065 -0.2794)
			(stroke
				(width 0.1)
				(type default)
			)
			(layer "B.Fab")
		)
		(fp_line
			(start 0.12065 0.2794)
			(end 0.12065 0.3048)
			(stroke
				(width 0.1)
				(type default)
			)
			(layer "B.Fab")
		)
		(fp_line
			(start 0.12065 0.3048)
			(end 0.67945 0.3048)
			(stroke
				(width 0.1)
				(type default)
			)
			(layer "B.Fab")
		)
		(fp_line
			(start 0.67945 -0.305054)
			(end 0.12065 -0.305054)
			(stroke
				(width 0.1)
				(type default)
			)
			(layer "B.Fab")
		)
		(fp_line
			(start 0.67945 0.3048)
			(end 0.67945 -0.305054)
			(stroke
				(width 0.1)
				(type default)
			)
			(layer "B.Fab")
		)
		(pad "1" smd circle
			(at 0.40005 0 180)
			(size 0 0)
			(layers "B.Cu" "B.Mask" "B.Paste")
			(net "PVDDCR_CPU1_P1")
		)
		(pad "2" smd circle
			(at -0.40005 0 180)
			(size 0 0)
			(layers "B.Cu" "B.Mask" "B.Paste")
			(net "GND")
		)
	)
)
